(kicad_pcb
	(version 20260206)
	(generator "pcbnew")
	(generator_version "10.0")
	(general
		(thickness 1.6)
		(legacy_teardrops no)
	)
	(paper "A4")
	(title_block
		(title "01162023_DA0F0TEBIF0_F0T_Expander_BD_F_brd_V02_OCP.brd")
		(comment 1 "Grand Teton / footprint 4451 of 9728 (PEX3), pads 1654-1767 of 2397")
	)
	(layers
		(0 "F.Cu" signal "TOP")
		(4 "In1.Cu" signal "GND")
		(6 "In2.Cu" signal "VCC")
		(8 "In3.Cu" signal "VCC1")
		(10 "In4.Cu" signal "GND1")
		(12 "In5.Cu" signal "IN1")
		(14 "In6.Cu" signal "GND2")
		(16 "In7.Cu" signal "IN2")
		(18 "In8.Cu" signal "GND3")
		(20 "In9.Cu" signal "IN3")
		(22 "In10.Cu" signal "GND4")
		(24 "In11.Cu" signal "IN4")
		(26 "In12.Cu" signal "GND5")
		(28 "In13.Cu" signal "IN5")
		(30 "In14.Cu" signal "GND6")
		(32 "In15.Cu" signal "IN6")
		(34 "In16.Cu" signal "GND7")
		(2 "B.Cu" signal "BOTTOM")
		(9 "F.Adhes" user "F.Adhesive")
		(11 "B.Adhes" user "B.Adhesive")
		(13 "F.Paste" user "Package Geometry/Pastemask Top")
		(15 "B.Paste" user "Package Geometry/Pastemask Bottom")
		(5 "F.SilkS" user "Ref Des/Silkscreen Top")
		(7 "B.SilkS" user "Ref Des/Silkscreen Bottom")
		(1 "F.Mask" user "Board Geometry/Soldermask Top")
		(3 "B.Mask" user "Board Geometry/Soldermask Bottom")
		(17 "Dwgs.User" user "User.Drawings")
		(19 "Cmts.User" user "User.Comments")
		(21 "Eco1.User" user "User.Eco1")
		(23 "Eco2.User" user "User.Eco2")
		(25 "Edge.Cuts" user "Board Geometry/Outline")
		(27 "Margin" user)
		(31 "F.CrtYd" user "Package Geometry/Place Bound Top")
		(29 "B.CrtYd" user "Package Geometry/Place Bound Bottom")
		(35 "F.Fab" user "Ref Des/Assembly Top")
		(33 "B.Fab" user "Ref Des/Assembly Bottom")
	)
	(footprint ""
		(layer "F.Cu")
		(at 407.949908 -295.89984)
		(property "Reference" "PEX3"
			(at -3.358642 35.5727 0)
			(unlocked yes)
			(layer "F.SilkS")
			(effects
				(font
					(size 2.032 1.524)
					(thickness 0.1524)
				)
				(justify left)
			)
		)
		(property "Value" ""
			(at 0 0 0)
			(layer "F.Fab")
			(effects
				(font
					(size 1.27 1.27)
				)
			)
		)
		(duplicate_pad_numbers_are_jumpers no)
		(pad "E41" smd circle
			(at 15.200122 -18.999962)
			(size 0.4572 0.4572)
			(layers "F.Cu" "F.Mask" "F.Paste")
			(net "GND")
		)
		(pad "E42" smd circle
			(at 16.150082 -18.999962)
			(size 0.4572 0.4572)
			(layers "F.Cu" "F.Mask" "F.Paste")
			(net "GND")
		)
		(pad "E43" smd circle
			(at 17.100042 -18.999962)
			(size 0.4572 0.4572)
			(layers "F.Cu" "F.Mask" "F.Paste")
			(net "GND")
		)
		(pad "E44" smd circle
			(at 18.050002 -18.999962)
			(size 0.4572 0.4572)
			(layers "F.Cu" "F.Mask" "F.Paste")
			(net "GND")
		)
		(pad "E45" smd circle
			(at 18.999962 -18.999962)
			(size 0.4572 0.4572)
			(layers "F.Cu" "F.Mask" "F.Paste")
			(net "GND")
		)
		(pad "E46" smd circle
			(at 19.949922 -18.999962)
			(size 0.4572 0.4572)
			(layers "F.Cu" "F.Mask" "F.Paste")
			(net "GND")
		)
		(pad "E47" smd circle
			(at 20.899882 -18.999962)
			(size 0.4572 0.4572)
			(layers "F.Cu" "F.Mask" "F.Paste")
			(net "GND")
		)
		(pad "E48" smd circle
			(at 21.850096 -18.999962)
			(size 0.4572 0.4572)
			(layers "F.Cu" "F.Mask" "F.Paste")
			(net "P5E_PEX3_STN4_TX_DP<71>")
		)
		(pad "E49" smd circle
			(at 22.800056 -18.999962)
			(size 0.4572 0.4572)
			(layers "F.Cu" "F.Mask" "F.Paste")
			(net "P5E_PEX3_STN4_TX_DN<71>")
		)
		(pad "F1" smd circle
			(at -22.800056 -18.050002)
			(size 0.4572 0.4572)
			(layers "F.Cu" "F.Mask" "F.Paste")
			(net "GND")
		)
		(pad "F2" smd circle
			(at -21.850096 -18.050002)
			(size 0.4572 0.4572)
			(layers "F.Cu" "F.Mask" "F.Paste")
			(net "GND")
		)
		(pad "F3" smd circle
			(at -20.899882 -18.050002)
			(size 0.4572 0.4572)
			(layers "F.Cu" "F.Mask" "F.Paste")
			(net "P5E_PEX3_STN7_TX_DN<123>")
		)
		(pad "F4" smd circle
			(at -19.949922 -18.050002)
			(size 0.4572 0.4572)
			(layers "F.Cu" "F.Mask" "F.Paste")
			(net "GND")
		)
		(pad "F5" smd circle
			(at -18.999962 -18.050002)
			(size 0.4572 0.4572)
			(layers "F.Cu" "F.Mask" "F.Paste")
			(net "P5E_PEX3_STN7_TX_DN<125>")
		)
		(pad "F6" smd circle
			(at -18.050002 -18.050002)
			(size 0.4572 0.4572)
			(layers "F.Cu" "F.Mask" "F.Paste")
			(net "GND")
		)
		(pad "F7" smd circle
			(at -17.100042 -18.050002)
			(size 0.4572 0.4572)
			(layers "F.Cu" "F.Mask" "F.Paste")
			(net "P5E_PEX3_STN7_TX_DN<127>")
		)
		(pad "F8" smd circle
			(at -16.150082 -18.050002)
			(size 0.4572 0.4572)
			(layers "F.Cu" "F.Mask" "F.Paste")
			(net "GND")
		)
		(pad "F9" smd circle
			(at -15.200122 -18.050002)
			(size 0.4572 0.4572)
			(layers "F.Cu" "F.Mask" "F.Paste")
			(net "P5E_PEX3_STN6_TX_DN<110>")
		)
		(pad "F10" smd circle
			(at -14.249908 -18.050002)
			(size 0.4572 0.4572)
			(layers "F.Cu" "F.Mask" "F.Paste")
			(net "GND")
		)
		(pad "F11" smd circle
			(at -13.299948 -18.050002)
			(size 0.4572 0.4572)
			(layers "F.Cu" "F.Mask" "F.Paste")
			(net "P5E_PEX3_STN6_TX_DN<108>")
		)
		(pad "F12" smd circle
			(at -12.349988 -18.050002)
			(size 0.4572 0.4572)
			(layers "F.Cu" "F.Mask" "F.Paste")
			(net "GND")
		)
		(pad "F13" smd circle
			(at -11.400028 -18.050002)
			(size 0.4572 0.4572)
			(layers "F.Cu" "F.Mask" "F.Paste")
			(net "P5E_PEX3_STN6_TX_DN<106>")
		)
		(pad "F14" smd circle
			(at -10.450068 -18.050002)
			(size 0.4572 0.4572)
			(layers "F.Cu" "F.Mask" "F.Paste")
			(net "GND")
		)
		(pad "F15" smd circle
			(at -9.500108 -18.050002)
			(size 0.4572 0.4572)
			(layers "F.Cu" "F.Mask" "F.Paste")
			(net "P5E_PEX3_STN6_TX_DN<104>")
		)
		(pad "F16" smd circle
			(at -8.549894 -18.050002)
			(size 0.4572 0.4572)
			(layers "F.Cu" "F.Mask" "F.Paste")
			(net "GND")
		)
		(pad "F17" smd circle
			(at -7.599934 -18.050002)
			(size 0.4572 0.4572)
			(layers "F.Cu" "F.Mask" "F.Paste")
			(net "P5E_PEX3_STN6_TX_DN<102>")
		)
		(pad "F18" smd circle
			(at -6.649974 -18.050002)
			(size 0.4572 0.4572)
			(layers "F.Cu" "F.Mask" "F.Paste")
			(net "GND")
		)
		(pad "F19" smd circle
			(at -5.700014 -18.050002)
			(size 0.4572 0.4572)
			(layers "F.Cu" "F.Mask" "F.Paste")
			(net "P5E_PEX3_STN6_TX_DN<100>")
		)
		(pad "F20" smd circle
			(at -4.750054 -18.050002)
			(size 0.4572 0.4572)
			(layers "F.Cu" "F.Mask" "F.Paste")
			(net "GND")
		)
		(pad "F21" smd circle
			(at -3.800094 -18.050002)
			(size 0.4572 0.4572)
			(layers "F.Cu" "F.Mask" "F.Paste")
			(net "P5E_PEX3_STN6_TX_DN<98>")
		)
		(pad "F22" smd circle
			(at -2.84988 -18.050002)
			(size 0.4572 0.4572)
			(layers "F.Cu" "F.Mask" "F.Paste")
			(net "GND")
		)
		(pad "F23" smd circle
			(at -1.89992 -18.050002)
			(size 0.4572 0.4572)
			(layers "F.Cu" "F.Mask" "F.Paste")
			(net "P5E_PEX3_STN6_TX_DN<96>")
		)
		(pad "F24" smd circle
			(at -0.94996 -18.050002)
			(size 0.4572 0.4572)
			(layers "F.Cu" "F.Mask" "F.Paste")
			(net "GND")
		)
		(pad "F25" smd circle
			(at 0 -18.050002)
			(size 0.4572 0.4572)
			(layers "F.Cu" "F.Mask" "F.Paste")
			(net "P5E_PEX3_STN5_TX_DN<81>")
		)
		(pad "F26" smd circle
			(at 0.94996 -18.050002)
			(size 0.4572 0.4572)
			(layers "F.Cu" "F.Mask" "F.Paste")
			(net "GND")
		)
		(pad "F27" smd circle
			(at 1.89992 -18.050002)
			(size 0.4572 0.4572)
			(layers "F.Cu" "F.Mask" "F.Paste")
			(net "P5E_PEX3_STN5_TX_DN<83>")
		)
		(pad "F28" smd circle
			(at 2.84988 -18.050002)
			(size 0.4572 0.4572)
			(layers "F.Cu" "F.Mask" "F.Paste")
			(net "GND")
		)
		(pad "F29" smd circle
			(at 3.800094 -18.050002)
			(size 0.4572 0.4572)
			(layers "F.Cu" "F.Mask" "F.Paste")
			(net "P5E_PEX3_STN5_TX_DN<85>")
		)
		(pad "F30" smd circle
			(at 4.750054 -18.050002)
			(size 0.4572 0.4572)
			(layers "F.Cu" "F.Mask" "F.Paste")
			(net "GND")
		)
		(pad "F31" smd circle
			(at 5.700014 -18.050002)
			(size 0.4572 0.4572)
			(layers "F.Cu" "F.Mask" "F.Paste")
			(net "P5E_PEX3_STN5_TX_DN<87>")
		)
		(pad "F32" smd circle
			(at 6.649974 -18.050002)
			(size 0.4572 0.4572)
			(layers "F.Cu" "F.Mask" "F.Paste")
			(net "GND")
		)
		(pad "F33" smd circle
			(at 7.599934 -18.050002)
			(size 0.4572 0.4572)
			(layers "F.Cu" "F.Mask" "F.Paste")
			(net "P5E_PEX3_STN5_TX_DN<89>")
		)
		(pad "F34" smd circle
			(at 8.549894 -18.050002)
			(size 0.4572 0.4572)
			(layers "F.Cu" "F.Mask" "F.Paste")
			(net "GND")
		)
		(pad "F35" smd circle
			(at 9.500108 -18.050002)
			(size 0.4572 0.4572)
			(layers "F.Cu" "F.Mask" "F.Paste")
			(net "P5E_PEX3_STN5_TX_DN<91>")
		)
		(pad "F36" smd circle
			(at 10.450068 -18.050002)
			(size 0.4572 0.4572)
			(layers "F.Cu" "F.Mask" "F.Paste")
			(net "GND")
		)
		(pad "F37" smd circle
			(at 11.400028 -18.050002)
			(size 0.4572 0.4572)
			(layers "F.Cu" "F.Mask" "F.Paste")
			(net "P5E_PEX3_STN5_TX_DN<93>")
		)
		(pad "F38" smd circle
			(at 12.349988 -18.050002)
			(size 0.4572 0.4572)
			(layers "F.Cu" "F.Mask" "F.Paste")
			(net "GND")
		)
		(pad "F39" smd circle
			(at 13.299948 -18.050002)
			(size 0.4572 0.4572)
			(layers "F.Cu" "F.Mask" "F.Paste")
			(net "P5E_PEX3_STN5_TX_DN<95>")
		)
		(pad "F40" smd circle
			(at 14.249908 -18.050002)
			(size 0.4572 0.4572)
			(layers "F.Cu" "F.Mask" "F.Paste")
			(net "GND")
		)
		(pad "F41" smd circle
			(at 15.200122 -18.050002)
			(size 0.4572 0.4572)
			(layers "F.Cu" "F.Mask" "F.Paste")
			(net "P5E_PEX3_STN4_TX_DN<78>")
		)
		(pad "F42" smd circle
			(at 16.150082 -18.050002)
			(size 0.4572 0.4572)
			(layers "F.Cu" "F.Mask" "F.Paste")
			(net "GND")
		)
		(pad "F43" smd circle
			(at 17.100042 -18.050002)
			(size 0.4572 0.4572)
			(layers "F.Cu" "F.Mask" "F.Paste")
			(net "P5E_PEX3_STN4_TX_DN<76>")
		)
		(pad "F44" smd circle
			(at 18.050002 -18.050002)
			(size 0.4572 0.4572)
			(layers "F.Cu" "F.Mask" "F.Paste")
			(net "GND")
		)
		(pad "F45" smd circle
			(at 18.999962 -18.050002)
			(size 0.4572 0.4572)
			(layers "F.Cu" "F.Mask" "F.Paste")
			(net "P5E_PEX3_STN4_TX_DN<74>")
		)
		(pad "F46" smd circle
			(at 19.949922 -18.050002)
			(size 0.4572 0.4572)
			(layers "F.Cu" "F.Mask" "F.Paste")
			(net "GND")
		)
		(pad "F47" smd circle
			(at 20.899882 -18.050002)
			(size 0.4572 0.4572)
			(layers "F.Cu" "F.Mask" "F.Paste")
			(net "P5E_PEX3_STN4_TX_DN<72>")
		)
		(pad "F48" smd circle
			(at 21.850096 -18.050002)
			(size 0.4572 0.4572)
			(layers "F.Cu" "F.Mask" "F.Paste")
			(net "GND")
		)
		(pad "F49" smd circle
			(at 22.800056 -18.050002)
			(size 0.4572 0.4572)
			(layers "F.Cu" "F.Mask" "F.Paste")
			(net "GND")
		)
		(pad "G1" smd circle
			(at -22.800056 -17.100042)
			(size 0.4572 0.4572)
			(layers "F.Cu" "F.Mask" "F.Paste")
			(net "GND")
		)
		(pad "G2" smd circle
			(at -21.850096 -17.100042)
			(size 0.4572 0.4572)
			(layers "F.Cu" "F.Mask" "F.Paste")
			(net "GND")
		)
		(pad "G3" smd circle
			(at -20.899882 -17.100042)
			(size 0.4572 0.4572)
			(layers "F.Cu" "F.Mask" "F.Paste")
			(net "P5E_PEX3_STN7_TX_DP<123>")
		)
		(pad "G4" smd circle
			(at -19.949922 -17.100042)
			(size 0.4572 0.4572)
			(layers "F.Cu" "F.Mask" "F.Paste")
			(net "GND")
		)
		(pad "G5" smd circle
			(at -18.999962 -17.100042)
			(size 0.4572 0.4572)
			(layers "F.Cu" "F.Mask" "F.Paste")
			(net "P5E_PEX3_STN7_TX_DP<125>")
		)
		(pad "G6" smd circle
			(at -18.050002 -17.100042)
			(size 0.4572 0.4572)
			(layers "F.Cu" "F.Mask" "F.Paste")
			(net "GND")
		)
		(pad "G7" smd circle
			(at -17.100042 -17.100042)
			(size 0.4572 0.4572)
			(layers "F.Cu" "F.Mask" "F.Paste")
			(net "P5E_PEX3_STN7_TX_DP<127>")
		)
		(pad "G8" smd circle
			(at -16.150082 -17.100042)
			(size 0.4572 0.4572)
			(layers "F.Cu" "F.Mask" "F.Paste")
			(net "GND")
		)
		(pad "G9" smd circle
			(at -15.200122 -17.100042)
			(size 0.4572 0.4572)
			(layers "F.Cu" "F.Mask" "F.Paste")
			(net "P5E_PEX3_STN6_TX_DP<110>")
		)
		(pad "G10" smd circle
			(at -14.249908 -17.100042)
			(size 0.4572 0.4572)
			(layers "F.Cu" "F.Mask" "F.Paste")
			(net "GND")
		)
		(pad "G11" smd circle
			(at -13.299948 -17.100042)
			(size 0.4572 0.4572)
			(layers "F.Cu" "F.Mask" "F.Paste")
			(net "P5E_PEX3_STN6_TX_DP<108>")
		)
		(pad "G12" smd circle
			(at -12.349988 -17.100042)
			(size 0.4572 0.4572)
			(layers "F.Cu" "F.Mask" "F.Paste")
			(net "GND")
		)
		(pad "G13" smd circle
			(at -11.400028 -17.100042)
			(size 0.4572 0.4572)
			(layers "F.Cu" "F.Mask" "F.Paste")
			(net "P5E_PEX3_STN6_TX_DP<106>")
		)
		(pad "G14" smd circle
			(at -10.450068 -17.100042)
			(size 0.4572 0.4572)
			(layers "F.Cu" "F.Mask" "F.Paste")
			(net "GND")
		)
		(pad "G15" smd circle
			(at -9.500108 -17.100042)
			(size 0.4572 0.4572)
			(layers "F.Cu" "F.Mask" "F.Paste")
			(net "P5E_PEX3_STN6_TX_DP<104>")
		)
		(pad "G16" smd circle
			(at -8.549894 -17.100042)
			(size 0.4572 0.4572)
			(layers "F.Cu" "F.Mask" "F.Paste")
			(net "GND")
		)
		(pad "G17" smd circle
			(at -7.599934 -17.100042)
			(size 0.4572 0.4572)
			(layers "F.Cu" "F.Mask" "F.Paste")
			(net "P5E_PEX3_STN6_TX_DP<102>")
		)
		(pad "G18" smd circle
			(at -6.649974 -17.100042)
			(size 0.4572 0.4572)
			(layers "F.Cu" "F.Mask" "F.Paste")
			(net "GND")
		)
		(pad "G19" smd circle
			(at -5.700014 -17.100042)
			(size 0.4572 0.4572)
			(layers "F.Cu" "F.Mask" "F.Paste")
			(net "P5E_PEX3_STN6_TX_DP<100>")
		)
		(pad "G20" smd circle
			(at -4.750054 -17.100042)
			(size 0.4572 0.4572)
			(layers "F.Cu" "F.Mask" "F.Paste")
			(net "GND")
		)
		(pad "G21" smd circle
			(at -3.800094 -17.100042)
			(size 0.4572 0.4572)
			(layers "F.Cu" "F.Mask" "F.Paste")
			(net "P5E_PEX3_STN6_TX_DP<98>")
		)
		(pad "G22" smd circle
			(at -2.84988 -17.100042)
			(size 0.4572 0.4572)
			(layers "F.Cu" "F.Mask" "F.Paste")
			(net "GND")
		)
		(pad "G23" smd circle
			(at -1.89992 -17.100042)
			(size 0.4572 0.4572)
			(layers "F.Cu" "F.Mask" "F.Paste")
			(net "P5E_PEX3_STN6_TX_DP<96>")
		)
		(pad "G24" smd circle
			(at -0.94996 -17.100042)
			(size 0.4572 0.4572)
			(layers "F.Cu" "F.Mask" "F.Paste")
			(net "GND")
		)
		(pad "G25" smd circle
			(at 0 -17.100042)
			(size 0.4572 0.4572)
			(layers "F.Cu" "F.Mask" "F.Paste")
			(net "P5E_PEX3_STN5_TX_DP<81>")
		)
		(pad "G26" smd circle
			(at 0.94996 -17.100042)
			(size 0.4572 0.4572)
			(layers "F.Cu" "F.Mask" "F.Paste")
			(net "GND")
		)
		(pad "G27" smd circle
			(at 1.89992 -17.100042)
			(size 0.4572 0.4572)
			(layers "F.Cu" "F.Mask" "F.Paste")
			(net "P5E_PEX3_STN5_TX_DP<83>")
		)
		(pad "G28" smd circle
			(at 2.84988 -17.100042)
			(size 0.4572 0.4572)
			(layers "F.Cu" "F.Mask" "F.Paste")
			(net "GND")
		)
		(pad "G29" smd circle
			(at 3.800094 -17.100042)
			(size 0.4572 0.4572)
			(layers "F.Cu" "F.Mask" "F.Paste")
			(net "P5E_PEX3_STN5_TX_DP<85>")
		)
		(pad "G30" smd circle
			(at 4.750054 -17.100042)
			(size 0.4572 0.4572)
			(layers "F.Cu" "F.Mask" "F.Paste")
			(net "GND")
		)
		(pad "G31" smd circle
			(at 5.700014 -17.100042)
			(size 0.4572 0.4572)
			(layers "F.Cu" "F.Mask" "F.Paste")
			(net "P5E_PEX3_STN5_TX_DP<87>")
		)
		(pad "G32" smd circle
			(at 6.649974 -17.100042)
			(size 0.4572 0.4572)
			(layers "F.Cu" "F.Mask" "F.Paste")
			(net "GND")
		)
		(pad "G33" smd circle
			(at 7.599934 -17.100042)
			(size 0.4572 0.4572)
			(layers "F.Cu" "F.Mask" "F.Paste")
			(net "P5E_PEX3_STN5_TX_DP<89>")
		)
		(pad "G34" smd circle
			(at 8.549894 -17.100042)
			(size 0.4572 0.4572)
			(layers "F.Cu" "F.Mask" "F.Paste")
			(net "GND")
		)
		(pad "G35" smd circle
			(at 9.500108 -17.100042)
			(size 0.4572 0.4572)
			(layers "F.Cu" "F.Mask" "F.Paste")
			(net "P5E_PEX3_STN5_TX_DP<91>")
		)
		(pad "G36" smd circle
			(at 10.450068 -17.100042)
			(size 0.4572 0.4572)
			(layers "F.Cu" "F.Mask" "F.Paste")
			(net "GND")
		)
		(pad "G37" smd circle
			(at 11.400028 -17.100042)
			(size 0.4572 0.4572)
			(layers "F.Cu" "F.Mask" "F.Paste")
			(net "P5E_PEX3_STN5_TX_DP<93>")
		)
		(pad "G38" smd circle
			(at 12.349988 -17.100042)
			(size 0.4572 0.4572)
			(layers "F.Cu" "F.Mask" "F.Paste")
			(net "GND")
		)
		(pad "G39" smd circle
			(at 13.299948 -17.100042)
			(size 0.4572 0.4572)
			(layers "F.Cu" "F.Mask" "F.Paste")
			(net "P5E_PEX3_STN5_TX_DP<95>")
		)
		(pad "G40" smd circle
			(at 14.249908 -17.100042)
			(size 0.4572 0.4572)
			(layers "F.Cu" "F.Mask" "F.Paste")
			(net "GND")
		)
		(pad "G41" smd circle
			(at 15.200122 -17.100042)
			(size 0.4572 0.4572)
			(layers "F.Cu" "F.Mask" "F.Paste")
			(net "P5E_PEX3_STN4_TX_DP<78>")
		)
		(pad "G42" smd circle
			(at 16.150082 -17.100042)
			(size 0.4572 0.4572)
			(layers "F.Cu" "F.Mask" "F.Paste")
			(net "GND")
		)
		(pad "G43" smd circle
			(at 17.100042 -17.100042)
			(size 0.4572 0.4572)
			(layers "F.Cu" "F.Mask" "F.Paste")
			(net "P5E_PEX3_STN4_TX_DP<76>")
		)
		(pad "G44" smd circle
			(at 18.050002 -17.100042)
			(size 0.4572 0.4572)
			(layers "F.Cu" "F.Mask" "F.Paste")
			(net "GND")
		)
		(pad "G45" smd circle
			(at 18.999962 -17.100042)
			(size 0.4572 0.4572)
			(layers "F.Cu" "F.Mask" "F.Paste")
			(net "P5E_PEX3_STN4_TX_DP<74>")
		)
		(pad "G46" smd circle
			(at 19.949922 -17.100042)
			(size 0.4572 0.4572)
			(layers "F.Cu" "F.Mask" "F.Paste")
			(net "GND")
		)
		(pad "G47" smd circle
			(at 20.899882 -17.100042)
			(size 0.4572 0.4572)
			(layers "F.Cu" "F.Mask" "F.Paste")
			(net "P5E_PEX3_STN4_TX_DP<72>")
		)
		(pad "G48" smd circle
			(at 21.850096 -17.100042)
			(size 0.4572 0.4572)
			(layers "F.Cu" "F.Mask" "F.Paste")
			(net "GND")
		)
		(pad "G49" smd circle
			(at 22.800056 -17.100042)
			(size 0.4572 0.4572)
			(layers "F.Cu" "F.Mask" "F.Paste")
			(net "GND")
		)
		(pad "H1" smd circle
			(at -22.800056 -16.150082)
			(size 0.4572 0.4572)
			(layers "F.Cu" "F.Mask" "F.Paste")
			(net "P5E_PEX3_STN7_TX_DN<121>")
		)
		(pad "H2" smd circle
			(at -21.850096 -16.150082)
			(size 0.4572 0.4572)
			(layers "F.Cu" "F.Mask" "F.Paste")
			(net "P5E_PEX3_STN7_TX_DP<121>")
		)
		(pad "H3" smd circle
			(at -20.899882 -16.150082)
			(size 0.4572 0.4572)
			(layers "F.Cu" "F.Mask" "F.Paste")
			(net "GND")
		)
		(pad "H4" smd circle
			(at -19.949922 -16.150082)
			(size 0.4572 0.4572)
			(layers "F.Cu" "F.Mask" "F.Paste")
			(net "P5E_PEX3_STN7_TX_DN<124>")
		)
		(pad "H5" smd circle
			(at -18.999962 -16.150082)
			(size 0.4572 0.4572)
			(layers "F.Cu" "F.Mask" "F.Paste")
			(net "GND")
		)
		(pad "H6" smd circle
			(at -18.050002 -16.150082)
			(size 0.4572 0.4572)
			(layers "F.Cu" "F.Mask" "F.Paste")
			(net "P5E_PEX3_STN7_TX_DN<126>")
		)
		(pad "H7" smd circle
			(at -17.100042 -16.150082)
			(size 0.4572 0.4572)
			(layers "F.Cu" "F.Mask" "F.Paste")
			(net "GND")
		)
	)
)
